(kicad_pcb
	(version 20260206)
	(generator "pcbnew")
	(generator_version "10.0")
	(general
		(thickness 1.6)
		(legacy_teardrops no)
	)
	(paper "A4")
	(title_block
		(title "Wiwynn_Tioga_Pass_MB.brd")
		(comment 1 "Tioga Pass / footprints 859-862 of 4770")
	)
	(layers
		(0 "F.Cu" signal "TOP")
		(4 "In1.Cu" signal "L2GND")
		(6 "In2.Cu" signal "L3")
		(8 "In3.Cu" signal "L4GND")
		(10 "In4.Cu" signal "L5")
		(12 "In5.Cu" signal "L6GND")
		(14 "In6.Cu" signal "L7VCC")
		(16 "In7.Cu" signal "L8VCC")
		(18 "In8.Cu" signal "L9GND")
		(20 "In9.Cu" signal "L10")
		(22 "In10.Cu" signal "L11GND")
		(24 "In11.Cu" signal "L12")
		(26 "In12.Cu" signal "L13GND")
		(2 "B.Cu" signal "BOTTOM")
		(9 "F.Adhes" user "F.Adhesive")
		(11 "B.Adhes" user "B.Adhesive")
		(13 "F.Paste" user "Package Geometry/Pastemask Top")
		(15 "B.Paste" user "Package Geometry/Pastemask Bottom")
		(5 "F.SilkS" user "Ref Des/Silkscreen Top")
		(7 "B.SilkS" user "Ref Des/Silkscreen Bottom")
		(1 "F.Mask" user "Board Geometry/Soldermask Top")
		(3 "B.Mask" user "Board Geometry/Soldermask Bottom")
		(17 "Dwgs.User" user "User.Drawings")
		(19 "Cmts.User" user "User.Comments")
		(21 "Eco1.User" user "User.Eco1")
		(23 "Eco2.User" user "User.Eco2")
		(25 "Edge.Cuts" user "Board Geometry/Outline")
		(27 "Margin" user)
		(31 "F.CrtYd" user "Package Geometry/Place Bound Top")
		(29 "B.CrtYd" user "Package Geometry/Place Bound Bottom")
		(35 "F.Fab" user "Ref Des/Assembly Top")
		(33 "B.Fab" user "Ref Des/Assembly Bottom")
	)
	(footprint ""
		(layer "F.Cu")
		(at 193.6369 -88.19642)
		(property "Reference" "R4D68"
			(at 0 0 0)
			(layer "F.SilkS")
			(hide yes)
			(effects
				(font
					(size 1.27 1.27)
				)
			)
		)
		(property "Value" ""
			(at 0 0 0)
			(layer "F.Fab")
			(effects
				(font
					(size 1.27 1.27)
				)
			)
		)
		(duplicate_pad_numbers_are_jumpers no)
		(fp_poly
			(pts
				(xy -0.2794 -0.1016) (xy 0.2794 -0.1016) (xy 0.2794 0.9906) (xy -0.2794 0.9906)
			)
			(stroke
				(width 0)
				(type default)
			)
			(fill no)
			(layer "F.CrtYd")
		)
		(fp_line
			(start -0.2794 -0.1016)
			(end -0.2794 0.9906)
			(stroke
				(width 0.1)
				(type default)
			)
			(layer "F.Fab")
		)
		(fp_line
			(start -0.2794 0.9906)
			(end 0.2794 0.9906)
			(stroke
				(width 0.1)
				(type default)
			)
			(layer "F.Fab")
		)
		(fp_line
			(start 0.2794 -0.1016)
			(end -0.2794 -0.1016)
			(stroke
				(width 0.1)
				(type default)
			)
			(layer "F.Fab")
		)
		(fp_line
			(start 0.2794 0.9906)
			(end 0.2794 -0.1016)
			(stroke
				(width 0.1)
				(type default)
			)
			(layer "F.Fab")
		)
		(pad "1" smd rect
			(at 0 0)
			(size 0.508 0.508)
			(layers "F.Cu" "F.Mask" "F.Paste")
			(net "VR_PVCCIN_CPU0_PH5_OCSET")
		)
		(pad "2" smd rect
			(at 0 0.889)
			(size 0.508 0.508)
			(layers "F.Cu" "F.Mask" "F.Paste")
			(net "GND")
		)
		(zone
			(layer "F.Cu")
			(hatch none 0.5)
			(connect_pads
				(clearance 0)
			)
			(min_thickness 0.25)
			(keepout
				(tracks allowed)
				(vias not_allowed)
				(pads allowed)
				(copperpour not_allowed)
				(footprints allowed)
			)
			(placement
				(enabled no)
				(sheetname "")
			)
			(fill
				(thermal_gap 0.5)
				(thermal_bridge_width 0.5)
				(island_removal_mode 0)
			)
			(polygon
				(pts
					(xy 193.3829 -87.94242) (xy 193.8909 -87.94242) (xy 193.8909 -87.56142) (xy 193.3829 -87.56142)
				)
			)
		)
		(zone
			(layer "F.Cu")
			(hatch none 0.5)
			(connect_pads
				(clearance 0)
			)
			(min_thickness 0.25)
			(keepout
				(tracks not_allowed)
				(vias allowed)
				(pads allowed)
				(copperpour not_allowed)
				(footprints allowed)
			)
			(placement
				(enabled no)
				(sheetname "")
			)
			(fill
				(thermal_gap 0.5)
				(thermal_bridge_width 0.5)
				(island_removal_mode 0)
			)
			(polygon
				(pts
					(xy 193.3829 -87.56142) (xy 193.8909 -87.56142) (xy 193.8909 -87.94242) (xy 193.3829 -87.94242)
				)
			)
		)
	)
	(footprint ""
		(layer "F.Cu")
		(at 496.000024 -141.849856 180)
		(property "Reference" "J9A2"
			(at -0.48768 -1.76403 0)
			(unlocked yes)
			(layer "B.SilkS")
			(effects
				(font
					(size 0.7874 0.5842)
					(thickness 0.1524)
				)
				(justify left mirror)
			)
		)
		(property "Value" ""
			(at 0 0 180)
			(layer "F.Fab")
			(effects
				(font
					(size 1.27 1.27)
				)
			)
		)
		(duplicate_pad_numbers_are_jumpers no)
		(fp_line
			(start 4.586478 14.254988)
			(end -2.078482 14.254988)
			(stroke
				(width 0.1524)
				(type default)
			)
			(layer "F.SilkS")
		)
		(fp_line
			(start 4.586478 13.302488)
			(end 4.586478 14.254988)
			(stroke
				(width 0.1524)
				(type default)
			)
			(layer "F.SilkS")
		)
		(fp_line
			(start 4.586478 7.777988)
			(end 4.078478 7.777988)
			(stroke
				(width 0.1524)
				(type default)
			)
			(layer "F.SilkS")
		)
		(fp_line
			(start 4.586478 4.221988)
			(end 4.586478 7.777988)
			(stroke
				(width 0.1524)
				(type default)
			)
			(layer "F.SilkS")
		)
		(fp_line
			(start 4.586478 -1.302512)
			(end 4.078478 -1.302512)
			(stroke
				(width 0.1524)
				(type default)
			)
			(layer "F.SilkS")
		)
		(fp_line
			(start 4.586478 -2.255012)
			(end 4.586478 -1.302512)
			(stroke
				(width 0.1524)
				(type default)
			)
			(layer "F.SilkS")
		)
		(fp_line
			(start 4.078478 13.302488)
			(end 4.586478 13.302488)
			(stroke
				(width 0.1524)
				(type default)
			)
			(layer "F.SilkS")
		)
		(fp_line
			(start 4.078478 7.777988)
			(end 4.078478 13.302488)
			(stroke
				(width 0.1524)
				(type default)
			)
			(layer "F.SilkS")
		)
		(fp_line
			(start 4.078478 4.221988)
			(end 4.586478 4.221988)
			(stroke
				(width 0.1524)
				(type default)
			)
			(layer "F.SilkS")
		)
		(fp_line
			(start 4.078478 -1.302512)
			(end 4.078478 4.221988)
			(stroke
				(width 0.1524)
				(type default)
			)
			(layer "F.SilkS")
		)
		(fp_line
			(start -2.078482 14.254988)
			(end -2.078482 -2.255012)
			(stroke
				(width 0.1524)
				(type default)
			)
			(layer "F.SilkS")
		)
		(fp_line
			(start -2.078482 -2.255012)
			(end 4.586478 -2.255012)
			(stroke
				(width 0.1524)
				(type default)
			)
			(layer "F.SilkS")
		)
		(fp_poly
			(pts
				(xy -4.7371 -0.247904) (xy -4.7371 0.77216) (xy -3.4671 0.262128)
			)
			(stroke
				(width 0)
				(type default)
			)
			(fill yes)
			(layer "F.SilkS")
		)
		(fp_poly
			(pts
				(xy -4.413758 -0.548894) (xy -4.413758 0.47117) (xy -3.143758 -0.038862)
			)
			(stroke
				(width 0)
				(type default)
			)
			(fill yes)
			(layer "B.SilkS")
		)
		(fp_poly
			(pts
				(xy -2.078482 14.254988) (xy -2.078482 -2.255012) (xy 4.586478 -2.255012) (xy 4.586478 -1.302512)
				(xy 4.078478 -1.302512) (xy 4.078478 4.221988) (xy 4.586478 4.221988) (xy 4.586478 7.777988) (xy 4.078478 7.777988)
				(xy 4.078478 13.302488) (xy 4.586478 13.302488) (xy 4.586478 14.254988)
			)
			(stroke
				(width 0)
				(type default)
			)
			(fill no)
			(layer "F.CrtYd")
		)
		(fp_poly
			(pts
				(xy -4.413758 -0.548894) (xy -4.413758 0.47117) (xy -3.143758 -0.038862)
			)
			(stroke
				(width 0)
				(type default)
			)
			(fill yes)
			(layer "B.Fab")
		)
		(fp_line
			(start 4.586478 14.254988)
			(end -2.078482 14.254988)
			(stroke
				(width 0.1)
				(type default)
			)
			(layer "F.Fab")
		)
		(fp_line
			(start 4.586478 13.302488)
			(end 4.586478 14.254988)
			(stroke
				(width 0.1)
				(type default)
			)
			(layer "F.Fab")
		)
		(fp_line
			(start 4.586478 7.777988)
			(end 4.078478 7.777988)
			(stroke
				(width 0.1)
				(type default)
			)
			(layer "F.Fab")
		)
		(fp_line
			(start 4.586478 4.221988)
			(end 4.586478 7.777988)
			(stroke
				(width 0.1)
				(type default)
			)
			(layer "F.Fab")
		)
		(fp_line
			(start 4.586478 -1.302512)
			(end 4.078478 -1.302512)
			(stroke
				(width 0.1)
				(type default)
			)
			(layer "F.Fab")
		)
		(fp_line
			(start 4.586478 -2.255012)
			(end 4.586478 -1.302512)
			(stroke
				(width 0.1)
				(type default)
			)
			(layer "F.Fab")
		)
		(fp_line
			(start 4.078478 13.302488)
			(end 4.586478 13.302488)
			(stroke
				(width 0.1)
				(type default)
			)
			(layer "F.Fab")
		)
		(fp_line
			(start 4.078478 7.777988)
			(end 4.078478 13.302488)
			(stroke
				(width 0.1)
				(type default)
			)
			(layer "F.Fab")
		)
		(fp_line
			(start 4.078478 4.221988)
			(end 4.586478 4.221988)
			(stroke
				(width 0.1)
				(type default)
			)
			(layer "F.Fab")
		)
		(fp_line
			(start 4.078478 -1.302512)
			(end 4.078478 4.221988)
			(stroke
				(width 0.1)
				(type default)
			)
			(layer "F.Fab")
		)
		(fp_line
			(start -2.078482 14.254988)
			(end -2.078482 -2.255012)
			(stroke
				(width 0.1)
				(type default)
			)
			(layer "F.Fab")
		)
		(fp_line
			(start -2.078482 -2.255012)
			(end 4.586478 -2.255012)
			(stroke
				(width 0.1)
				(type default)
			)
			(layer "F.Fab")
		)
		(fp_poly
			(pts
				(xy -4.413758 -0.548894) (xy -4.413758 0.47117) (xy -3.143758 -0.038862)
			)
			(stroke
				(width 0)
				(type default)
			)
			(fill yes)
			(layer "F.Fab")
		)
		(fp_text user "14"
			(at 3.575304 15.148814 0)
			(unlocked yes)
			(layer "F.SilkS")
			(effects
				(font
					(size 0.7874 0.5842)
					(thickness 0.1524)
				)
				(justify left)
			)
		)
		(fp_text user "13"
			(at -0.070866 15.158212 0)
			(unlocked yes)
			(layer "F.SilkS")
			(effects
				(font
					(size 0.635 0.635)
					(thickness 0.1524)
				)
				(justify left)
			)
		)
		(fp_text user "2"
			(at -2.446274 -0.19304 0)
			(unlocked yes)
			(layer "F.SilkS")
			(effects
				(font
					(size 0.635 0.635)
					(thickness 0.1524)
				)
				(justify left)
			)
		)
		(fp_text user "2"
			(at 3.468624 0.874014 180)
			(unlocked yes)
			(layer "B.SilkS")
			(effects
				(font
					(size 0.7874 0.5842)
					(thickness 0.1524)
				)
				(justify left mirror)
			)
		)
		(fp_text user "14"
			(at 1.72974 13.92809 0)
			(unlocked yes)
			(layer "B.SilkS")
			(effects
				(font
					(size 0.7874 0.5842)
					(thickness 0.1524)
				)
				(justify left mirror)
			)
		)
		(fp_text user "13"
			(at -1.53162 13.89761 0)
			(unlocked yes)
			(layer "B.SilkS")
			(effects
				(font
					(size 0.7874 0.5842)
					(thickness 0.1524)
				)
				(justify left mirror)
			)
		)
		(fp_text user "14"
			(at 6.467348 12.166219 180)
			(unlocked yes)
			(layer "B.Fab")
			(effects
				(font
					(size 0.78994 0.579882)
					(thickness 0.000001)
				)
				(justify left mirror)
			)
		)
		(fp_text user "2"
			(at 5.705602 -0.255397 180)
			(unlocked yes)
			(layer "B.Fab")
			(effects
				(font
					(size 0.78994 0.579882)
					(thickness 0.000001)
				)
				(justify left mirror)
			)
		)
		(fp_text user "13"
			(at -2.924048 12.094845 180)
			(unlocked yes)
			(layer "B.Fab")
			(effects
				(font
					(size 0.78994 0.579882)
					(thickness 0.000001)
				)
				(justify left mirror)
			)
		)
		(fp_text user "14"
			(at 5.82295 0.990346 0)
			(unlocked yes)
			(layer "F.Fab")
			(effects
				(font
					(size 0.635 0.635)
					(thickness 0.1524)
				)
				(justify left)
			)
		)
		(fp_text user "13"
			(at -0.069088 15.159482 0)
			(unlocked yes)
			(layer "F.Fab")
			(effects
				(font
					(size 0.635 0.635)
					(thickness 0.1524)
				)
				(justify left)
			)
		)
		(fp_text user "2"
			(at -0.148082 -3.03784 0)
			(unlocked yes)
			(layer "F.Fab")
			(effects
				(font
					(size 0.635 0.635)
					(thickness 0.1524)
				)
				(justify left)
			)
		)
		(pad "1" thru_hole rect
			(at 0 0 180)
			(size 1.397 1.397)
			(drill 1.016)
			(layers "*.Cu" "*.Mask")
			(remove_unused_layers no)
			(net "LED_POSTCODE_0_R")
			(clearance 0.127)
			(thermal_gap 0.127)
			(padstack
				(mode front_inner_back)
				(layer "Inner"
					(shape circle)
					(size 1.397 1.397)
					(clearance 0.127)
				)
				(layer "B.Cu"
					(shape rect)
					(size 1.397 1.397)
					(clearance 0.127)
				)
			)
		)
		(pad "2" thru_hole circle
			(at 1.999996 0 180)
			(size 1.397 1.397)
			(drill 1.016)
			(layers "*.Cu" "*.Mask")
			(remove_unused_layers no)
			(net "LED_POSTCODE_1_R")
			(clearance 0.127)
			(thermal_gap 0.127)
		)
		(pad "3" thru_hole circle
			(at 0 1.999996 180)
			(size 1.397 1.397)
			(drill 1.016)
			(layers "*.Cu" "*.Mask")
			(remove_unused_layers no)
			(net "LED_POSTCODE_2_R")
			(clearance 0.127)
			(thermal_gap 0.127)
		)
		(pad "4" thru_hole circle
			(at 1.999996 1.999996 180)
			(size 1.397 1.397)
			(drill 1.016)
			(layers "*.Cu" "*.Mask")
			(remove_unused_layers no)
			(net "LED_POSTCODE_3_R")
			(clearance 0.127)
			(thermal_gap 0.127)
		)
		(pad "5" thru_hole circle
			(at 0 3.999992 180)
			(size 1.397 1.397)
			(drill 1.016)
			(layers "*.Cu" "*.Mask")
			(remove_unused_layers no)
			(net "LED_POSTCODE_4_R")
			(clearance 0.127)
			(thermal_gap 0.127)
		)
		(pad "6" thru_hole circle
			(at 1.999996 3.999992 180)
			(size 1.397 1.397)
			(drill 1.016)
			(layers "*.Cu" "*.Mask")
			(remove_unused_layers no)
			(net "LED_POSTCODE_5_R")
			(clearance 0.127)
			(thermal_gap 0.127)
		)
		(pad "7" thru_hole circle
			(at 0 5.999988 180)
			(size 1.397 1.397)
			(drill 1.016)
			(layers "*.Cu" "*.Mask")
			(remove_unused_layers no)
			(net "LED_POSTCODE_6_R")
			(clearance 0.127)
			(thermal_gap 0.127)
		)
		(pad "8" thru_hole circle
			(at 1.999996 5.999988 180)
			(size 1.397 1.397)
			(drill 1.016)
			(layers "*.Cu" "*.Mask")
			(remove_unused_layers no)
			(net "LED_POSTCODE_7_R")
			(clearance 0.127)
			(thermal_gap 0.127)
		)
		(pad "9" thru_hole circle
			(at 0 7.999984 180)
			(size 1.397 1.397)
			(drill 1.016)
			(layers "*.Cu" "*.Mask")
			(remove_unused_layers no)
			(net "SPA_MID_DBG1_TX")
			(clearance 0.127)
			(thermal_gap 0.127)
		)
		(pad "10" thru_hole circle
			(at 1.999996 7.999984 180)
			(size 1.397 1.397)
			(drill 1.016)
			(layers "*.Cu" "*.Mask")
			(remove_unused_layers no)
			(net "SPA_5V_SIN_SW")
			(clearance 0.127)
			(thermal_gap 0.127)
		)
		(pad "11" thru_hole circle
			(at 0 9.99998 180)
			(size 1.397 1.397)
			(drill 1.016)
			(layers "*.Cu" "*.Mask")
			(remove_unused_layers no)
			(net "FM_DEBUG_RST_BTN_N")
			(clearance 0.127)
			(thermal_gap 0.127)
		)
		(pad "12" thru_hole circle
			(at 1.999996 9.99998 180)
			(size 1.397 1.397)
			(drill 1.016)
			(layers "*.Cu" "*.Mask")
			(remove_unused_layers no)
			(net "FM_UART_SWITCH_N")
			(clearance 0.127)
			(thermal_gap 0.127)
		)
		(pad "13" thru_hole circle
			(at 0 11.999976 180)
			(size 1.397 1.397)
			(drill 1.016)
			(layers "*.Cu" "*.Mask")
			(remove_unused_layers no)
			(net "GND")
			(clearance 0.127)
			(thermal_gap 0.127)
		)
		(pad "14" thru_hole circle
			(at 1.999996 11.999976 180)
			(size 1.397 1.397)
			(drill 1.016)
			(layers "*.Cu" "*.Mask")
			(remove_unused_layers no)
			(net "P5V_STBY_DGB_FS")
			(clearance 0.127)
			(thermal_gap 0.127)
		)
	)
	(footprint ""
		(layer "F.Cu")
		(at 391.403078 -86.569042)
		(property "Reference" "R8D5"
			(at 0 0 0)
			(layer "F.SilkS")
			(hide yes)
			(effects
				(font
					(size 1.27 1.27)
				)
			)
		)
		(property "Value" ""
			(at 0 0 0)
			(layer "F.Fab")
			(effects
				(font
					(size 1.27 1.27)
				)
			)
		)
		(duplicate_pad_numbers_are_jumpers no)
		(fp_poly
			(pts
				(xy -0.2794 -0.1016) (xy 0.2794 -0.1016) (xy 0.2794 0.9906) (xy -0.2794 0.9906)
			)
			(stroke
				(width 0)
				(type default)
			)
			(fill no)
			(layer "F.CrtYd")
		)
		(fp_line
			(start -0.2794 -0.1016)
			(end -0.2794 0.9906)
			(stroke
				(width 0.1)
				(type default)
			)
			(layer "F.Fab")
		)
		(fp_line
			(start -0.2794 0.9906)
			(end 0.2794 0.9906)
			(stroke
				(width 0.1)
				(type default)
			)
			(layer "F.Fab")
		)
		(fp_line
			(start 0.2794 -0.1016)
			(end -0.2794 -0.1016)
			(stroke
				(width 0.1)
				(type default)
			)
			(layer "F.Fab")
		)
		(fp_line
			(start 0.2794 0.9906)
			(end 0.2794 -0.1016)
			(stroke
				(width 0.1)
				(type default)
			)
			(layer "F.Fab")
		)
		(pad "1" smd rect
			(at 0 0)
			(size 0.508 0.508)
			(layers "F.Cu" "F.Mask" "F.Paste")
			(net "PU_ADR_TIMER_HOLD_OFF_N")
		)
		(pad "2" smd rect
			(at 0 0.889)
			(size 0.508 0.508)
			(layers "F.Cu" "F.Mask" "F.Paste")
			(net "GND")
		)
		(zone
			(layer "F.Cu")
			(hatch none 0.5)
			(connect_pads
				(clearance 0)
			)
			(min_thickness 0.25)
			(keepout
				(tracks allowed)
				(vias not_allowed)
				(pads allowed)
				(copperpour not_allowed)
				(footprints allowed)
			)
			(placement
				(enabled no)
				(sheetname "")
			)
			(fill
				(thermal_gap 0.5)
				(thermal_bridge_width 0.5)
				(island_removal_mode 0)
			)
			(polygon
				(pts
					(xy 391.149078 -86.315042) (xy 391.657078 -86.315042) (xy 391.657078 -85.934042) (xy 391.149078 -85.934042)
				)
			)
		)
		(zone
			(layer "F.Cu")
			(hatch none 0.5)
			(connect_pads
				(clearance 0)
			)
			(min_thickness 0.25)
			(keepout
				(tracks not_allowed)
				(vias allowed)
				(pads allowed)
				(copperpour not_allowed)
				(footprints allowed)
			)
			(placement
				(enabled no)
				(sheetname "")
			)
			(fill
				(thermal_gap 0.5)
				(thermal_bridge_width 0.5)
				(island_removal_mode 0)
			)
			(polygon
				(pts
					(xy 391.149078 -85.934042) (xy 391.657078 -85.934042) (xy 391.657078 -86.315042) (xy 391.149078 -86.315042)
				)
			)
		)
	)
	(footprint ""
		(layer "F.Cu")
		(at 369.2652 -92.1766 180)
		(property "Reference" "U7D1"
			(at 0.28194 -1.71323 180)
			(unlocked yes)
			(layer "F.SilkS")
			(effects
				(font
					(size 0.7874 0.5842)
					(thickness 0.1524)
				)
				(justify left)
			)
		)
		(property "Value" ""
			(at 0 0 180)
			(layer "F.Fab")
			(effects
				(font
					(size 1.27 1.27)
				)
			)
		)
		(duplicate_pad_numbers_are_jumpers no)
		(fp_circle
			(center -0.4699 -0.8382)
			(end -0.5969 -0.8382)
			(stroke
				(width 0.254)
				(type default)
			)
			(fill no)
			(layer "F.SilkS")
		)
		(fp_poly
			(pts
				(xy 0.21463 -0.450088) (xy 1.56337 -0.450088) (xy 1.56337 1.75006) (xy 0.21463 1.75006)
			)
			(stroke
				(width 0)
				(type default)
			)
			(fill no)
			(layer "F.CrtYd")
		)
		(fp_line
			(start 1.56337 1.75006)
			(end 0.21463 1.75006)
			(stroke
				(width 0.1)
				(type default)
			)
			(layer "F.Fab")
		)
		(fp_line
			(start 1.56337 -0.450088)
			(end 1.56337 1.75006)
			(stroke
				(width 0.1)
				(type default)
			)
			(layer "F.Fab")
		)
		(fp_line
			(start 0.21463 1.75006)
			(end 0.21463 -0.450088)
			(stroke
				(width 0.1)
				(type default)
			)
			(layer "F.Fab")
		)
		(fp_line
			(start 0.21463 -0.450088)
			(end 1.56337 -0.450088)
			(stroke
				(width 0.1)
				(type default)
			)
			(layer "F.Fab")
		)
		(fp_circle
			(center -0.4699 -0.8382)
			(end -0.5969 -0.8382)
			(stroke
				(width 0.254)
				(type default)
			)
			(fill no)
			(layer "F.Fab")
		)
		(pad "1" smd rect
			(at 0 0 180)
			(size 1.016 0.381)
			(layers "F.Cu" "F.Mask" "F.Paste")
			(net "PWRGD_PVCCIO_CPU0")
		)
		(pad "2" smd rect
			(at 0 0.649986 180)
			(size 1.016 0.381)
			(layers "F.Cu" "F.Mask" "F.Paste")
			(net "XDP_PCH_PWR_DEBUG_N")
		)
		(pad "3" smd rect
			(at 0 1.299972 180)
			(size 1.016 0.381)
			(layers "F.Cu" "F.Mask" "F.Paste")
			(net "GND")
		)
		(pad "4" smd rect
			(at 1.778 1.299972 180)
			(size 1.016 0.381)
			(layers "F.Cu" "F.Mask" "F.Paste")
			(net "XDP_CPU_PWR_DEBUG_N")
		)
		(pad "5" smd rect
			(at 1.778 0 180)
			(size 1.016 0.381)
			(layers "F.Cu" "F.Mask" "F.Paste")
			(net "P3V3_STBY")
		)
	)
)
